(kicad_pcb
	(version 20260206)
	(generator "pcbnew")
	(generator_version "10.0")
	(general
		(thickness 1.6)
		(legacy_teardrops no)
	)
	(paper "A4")
	(title_block
		(title "v1-chassis-manager — T6M_CM_d_v01_1031_1645.brd")
		(comment 1 "Open CloudServer (Microsoft) / footprints 441-449 of 2512")
	)
	(layers
		(0 "F.Cu" signal "TOP")
		(4 "In1.Cu" signal "GND1")
		(6 "In2.Cu" signal "IN1")
		(8 "In3.Cu" signal "VCC1")
		(10 "In4.Cu" signal "VCC2")
		(12 "In5.Cu" signal "GND2")
		(14 "In6.Cu" signal "IN2")
		(16 "In7.Cu" signal "IN3")
		(18 "In8.Cu" signal "GND3")
		(2 "B.Cu" signal "BOTTOM")
		(9 "F.Adhes" user "F.Adhesive")
		(11 "B.Adhes" user "B.Adhesive")
		(13 "F.Paste" user "Package Geometry/Pastemask Top")
		(15 "B.Paste" user "Package Geometry/Pastemask Bottom")
		(5 "F.SilkS" user "Ref Des/Silkscreen Top")
		(7 "B.SilkS" user "Ref Des/Silkscreen Bottom")
		(1 "F.Mask" user "Board Geometry/Soldermask Top")
		(3 "B.Mask" user "Board Geometry/Soldermask Bottom")
		(17 "Dwgs.User" user "User.Drawings")
		(19 "Cmts.User" user "User.Comments")
		(21 "Eco1.User" user "User.Eco1")
		(23 "Eco2.User" user "User.Eco2")
		(25 "Edge.Cuts" user "Board Geometry/Outline")
		(27 "Margin" user)
		(31 "F.CrtYd" user "Package Geometry/Place Bound Top")
		(29 "B.CrtYd" user "Package Geometry/Place Bound Bottom")
		(35 "F.Fab" user "Ref Des/Assembly Top")
		(33 "B.Fab" user "Ref Des/Assembly Bottom")
	)
	(footprint ""
		(layer "F.Cu")
		(at 42.636694 -108.133134 -90)
		(property "Reference" "PC20"
			(at 0.09398 3.523234 0)
			(unlocked yes)
			(layer "F.SilkS")
			(effects
				(font
					(size 0.7874 0.5842)
					(thickness 0.1524)
				)
				(justify left)
			)
		)
		(property "Value" ""
			(at 0 0 270)
			(layer "F.Fab")
			(effects
				(font
					(size 1.27 1.27)
				)
			)
		)
		(duplicate_pad_numbers_are_jumpers no)
		(fp_line
			(start -0.7874 0.4064)
			(end -0.7874 -0.4064)
			(stroke
				(width 0.1524)
				(type default)
			)
			(layer "F.SilkS")
		)
		(fp_line
			(start 0.7874 0.4064)
			(end -0.7874 0.4064)
			(stroke
				(width 0.1524)
				(type default)
			)
			(layer "F.SilkS")
		)
		(fp_line
			(start 0 0.381)
			(end 0 -0.381)
			(stroke
				(width 0.1524)
				(type default)
			)
			(layer "F.SilkS")
		)
		(fp_line
			(start -0.7874 -0.4064)
			(end 0.7874 -0.4064)
			(stroke
				(width 0.1524)
				(type default)
			)
			(layer "F.SilkS")
		)
		(fp_line
			(start 0.7874 -0.4064)
			(end 0.7874 0.4064)
			(stroke
				(width 0.1524)
				(type default)
			)
			(layer "F.SilkS")
		)
		(fp_poly
			(pts
				(xy -0.5334 0.254) (xy -0.635 0.254) (xy -0.635 0.2286) (xy -0.635 -0.254) (xy -0.5334 -0.254) (xy -0.5334 -0.2794)
				(xy 0.5334 -0.2794) (xy 0.5334 -0.254) (xy 0.635 -0.254) (xy 0.635 0.254) (xy 0.5334 0.254) (xy 0.5334 0.2794)
				(xy -0.508 0.2794) (xy -0.5334 0.2794)
			)
			(stroke
				(width 0)
				(type default)
			)
			(fill no)
			(layer "F.CrtYd")
		)
		(pad "1" smd rect
			(at 0.40005 0 270)
			(size 0.4572 0.508)
			(layers "F.Cu" "F.Mask" "F.Paste")
			(net "GND")
		)
		(pad "2" smd rect
			(at -0.40005 0 270)
			(size 0.4572 0.508)
			(layers "F.Cu" "F.Mask" "F.Paste")
			(net "P3V3_STB_NODE1_SS")
		)
	)
	(footprint ""
		(layer "F.Cu")
		(at 91.102434 -184.794398 180)
		(property "Reference" "C687"
			(at 1.458214 7.09041 0)
			(unlocked yes)
			(layer "F.SilkS")
			(effects
				(font
					(size 0.7874 0.5842)
					(thickness 0.1524)
				)
				(justify left)
			)
		)
		(property "Value" ""
			(at 0 0 180)
			(layer "F.Fab")
			(effects
				(font
					(size 1.27 1.27)
				)
			)
		)
		(duplicate_pad_numbers_are_jumpers no)
		(fp_line
			(start 0.7874 0.4064)
			(end -0.7874 0.4064)
			(stroke
				(width 0.1524)
				(type default)
			)
			(layer "F.SilkS")
		)
		(fp_line
			(start 0.7874 -0.4064)
			(end 0.7874 0.4064)
			(stroke
				(width 0.1524)
				(type default)
			)
			(layer "F.SilkS")
		)
		(fp_line
			(start 0 0.381)
			(end 0 -0.381)
			(stroke
				(width 0.1524)
				(type default)
			)
			(layer "F.SilkS")
		)
		(fp_line
			(start -0.7874 0.4064)
			(end -0.7874 -0.4064)
			(stroke
				(width 0.1524)
				(type default)
			)
			(layer "F.SilkS")
		)
		(fp_line
			(start -0.7874 -0.4064)
			(end 0.7874 -0.4064)
			(stroke
				(width 0.1524)
				(type default)
			)
			(layer "F.SilkS")
		)
		(fp_poly
			(pts
				(xy -0.5334 0.254) (xy -0.635 0.254) (xy -0.635 0.2286) (xy -0.635 -0.254) (xy -0.5334 -0.254) (xy -0.5334 -0.2794)
				(xy 0.5334 -0.2794) (xy 0.5334 -0.254) (xy 0.635 -0.254) (xy 0.635 0.254) (xy 0.5334 0.254) (xy 0.5334 0.2794)
				(xy -0.508 0.2794) (xy -0.5334 0.2794)
			)
			(stroke
				(width 0)
				(type default)
			)
			(fill no)
			(layer "F.CrtYd")
		)
		(pad "1" smd rect
			(at 0.40005 0 180)
			(size 0.4572 0.508)
			(layers "F.Cu" "F.Mask" "F.Paste")
			(net "UART_T5_NODE3_TXD_R")
		)
		(pad "2" smd rect
			(at -0.40005 0 180)
			(size 0.4572 0.508)
			(layers "F.Cu" "F.Mask" "F.Paste")
			(net "GND")
		)
	)
	(footprint ""
		(layer "F.Cu")
		(at 114.046254 -62.271148 180)
		(property "Reference" "R228"
			(at -1.25349 -1.859788 0)
			(unlocked yes)
			(layer "F.SilkS")
			(effects
				(font
					(size 0.7874 0.5842)
					(thickness 0.1524)
				)
				(justify left)
			)
		)
		(property "Value" ""
			(at 0 0 180)
			(layer "F.Fab")
			(effects
				(font
					(size 1.27 1.27)
				)
			)
		)
		(duplicate_pad_numbers_are_jumpers no)
		(fp_line
			(start 0.7874 0.4064)
			(end -0.7874 0.4064)
			(stroke
				(width 0.1524)
				(type default)
			)
			(layer "F.SilkS")
		)
		(fp_line
			(start 0.7874 -0.4064)
			(end 0.7874 0.4064)
			(stroke
				(width 0.1524)
				(type default)
			)
			(layer "F.SilkS")
		)
		(fp_line
			(start -0.7874 0.4064)
			(end -0.7874 -0.4064)
			(stroke
				(width 0.1524)
				(type default)
			)
			(layer "F.SilkS")
		)
		(fp_line
			(start -0.7874 -0.4064)
			(end 0.7874 -0.4064)
			(stroke
				(width 0.1524)
				(type default)
			)
			(layer "F.SilkS")
		)
		(fp_poly
			(pts
				(xy -0.508 0.2794) (xy -0.508 0.2286) (xy -0.635 0.2286) (xy -0.635 -0.254) (xy -0.5334 -0.254)
				(xy -0.5334 -0.2794) (xy 0.5334 -0.2794) (xy 0.5334 -0.254) (xy 0.635 -0.254) (xy 0.635 0.254) (xy 0.5334 0.254)
				(xy 0.5334 0.2794)
			)
			(stroke
				(width 0)
				(type default)
			)
			(fill no)
			(layer "F.CrtYd")
		)
		(pad "1" smd rect
			(at 0.40005 0 180)
			(size 0.4572 0.508)
			(layers "F.Cu" "F.Mask" "F.Paste")
			(net "XDP_SOC_CPU_NODE1_TDO")
		)
		(pad "2" smd rect
			(at -0.40005 0 180)
			(size 0.4572 0.508)
			(layers "F.Cu" "F.Mask" "F.Paste")
			(net "P1V05_NODE1")
		)
	)
	(footprint ""
		(layer "F.Cu")
		(at 119.538242 -39.53764 -90)
		(property "Reference" "R815"
			(at 6.720332 -0.181864 90)
			(unlocked yes)
			(layer "F.SilkS")
			(effects
				(font
					(size 0.7874 0.5842)
					(thickness 0.1524)
				)
				(justify left)
			)
		)
		(property "Value" ""
			(at 0 0 270)
			(layer "F.Fab")
			(effects
				(font
					(size 1.27 1.27)
				)
			)
		)
		(duplicate_pad_numbers_are_jumpers no)
		(fp_line
			(start -0.7874 0.4064)
			(end -0.7874 -0.4064)
			(stroke
				(width 0.1524)
				(type default)
			)
			(layer "F.SilkS")
		)
		(fp_line
			(start 0.7874 0.4064)
			(end -0.7874 0.4064)
			(stroke
				(width 0.1524)
				(type default)
			)
			(layer "F.SilkS")
		)
		(fp_line
			(start -0.7874 -0.4064)
			(end 0.7874 -0.4064)
			(stroke
				(width 0.1524)
				(type default)
			)
			(layer "F.SilkS")
		)
		(fp_line
			(start 0.7874 -0.4064)
			(end 0.7874 0.4064)
			(stroke
				(width 0.1524)
				(type default)
			)
			(layer "F.SilkS")
		)
		(fp_poly
			(pts
				(xy -0.508 0.2794) (xy -0.508 0.2286) (xy -0.635 0.2286) (xy -0.635 -0.254) (xy -0.5334 -0.254)
				(xy -0.5334 -0.2794) (xy 0.5334 -0.2794) (xy 0.5334 -0.254) (xy 0.635 -0.254) (xy 0.635 0.254) (xy 0.5334 0.254)
				(xy 0.5334 0.2794)
			)
			(stroke
				(width 0)
				(type default)
			)
			(fill no)
			(layer "F.CrtYd")
		)
		(pad "1" smd rect
			(at 0.40005 0 270)
			(size 0.4572 0.508)
			(layers "F.Cu" "F.Mask" "F.Paste")
			(net "CLK_48M_SIO")
		)
		(pad "2" smd rect
			(at -0.40005 0 270)
			(size 0.4572 0.508)
			(layers "F.Cu" "F.Mask" "F.Paste")
			(net "SIO_CLKIN")
		)
	)
	(footprint ""
		(layer "F.Cu")
		(at 53.561996 -157.982158)
		(property "Reference" "R596"
			(at -0.575564 -5.34035 0)
			(unlocked yes)
			(layer "F.SilkS")
			(effects
				(font
					(size 0.7874 0.5842)
					(thickness 0.1524)
				)
				(justify left)
			)
		)
		(property "Value" ""
			(at 0 0 0)
			(layer "F.Fab")
			(effects
				(font
					(size 1.27 1.27)
				)
			)
		)
		(duplicate_pad_numbers_are_jumpers no)
		(fp_line
			(start -0.7874 -0.4064)
			(end 0.7874 -0.4064)
			(stroke
				(width 0.1524)
				(type default)
			)
			(layer "F.SilkS")
		)
		(fp_line
			(start -0.7874 0.4064)
			(end -0.7874 -0.4064)
			(stroke
				(width 0.1524)
				(type default)
			)
			(layer "F.SilkS")
		)
		(fp_line
			(start 0.7874 -0.4064)
			(end 0.7874 0.4064)
			(stroke
				(width 0.1524)
				(type default)
			)
			(layer "F.SilkS")
		)
		(fp_line
			(start 0.7874 0.4064)
			(end -0.7874 0.4064)
			(stroke
				(width 0.1524)
				(type default)
			)
			(layer "F.SilkS")
		)
		(fp_poly
			(pts
				(xy -0.508 0.2794) (xy -0.508 0.2286) (xy -0.635 0.2286) (xy -0.635 -0.254) (xy -0.5334 -0.254)
				(xy -0.5334 -0.2794) (xy 0.5334 -0.2794) (xy 0.5334 -0.254) (xy 0.635 -0.254) (xy 0.635 0.254) (xy 0.5334 0.254)
				(xy 0.5334 0.2794)
			)
			(stroke
				(width 0)
				(type default)
			)
			(fill no)
			(layer "F.CrtYd")
		)
		(pad "1" smd rect
			(at 0.40005 0)
			(size 0.4572 0.508)
			(layers "F.Cu" "F.Mask" "F.Paste")
			(net "P3V3_NODE1")
		)
		(pad "2" smd rect
			(at -0.40005 0)
			(size 0.4572 0.508)
			(layers "F.Cu" "F.Mask" "F.Paste")
			(net "LAN1_DISABLE_N")
		)
	)
	(footprint ""
		(layer "F.Cu")
		(at 193.143886 -142.116302 180)
		(property "Reference" "C460"
			(at -2.05232 -0.462026 0)
			(unlocked yes)
			(layer "F.SilkS")
			(effects
				(font
					(size 0.7874 0.5842)
					(thickness 0.1524)
				)
				(justify left)
			)
		)
		(property "Value" ""
			(at 0 0 180)
			(layer "F.Fab")
			(effects
				(font
					(size 1.27 1.27)
				)
			)
		)
		(duplicate_pad_numbers_are_jumpers no)
		(fp_line
			(start 0.7874 0.4064)
			(end -0.7874 0.4064)
			(stroke
				(width 0.1524)
				(type default)
			)
			(layer "F.SilkS")
		)
		(fp_line
			(start 0.7874 -0.4064)
			(end 0.7874 0.4064)
			(stroke
				(width 0.1524)
				(type default)
			)
			(layer "F.SilkS")
		)
		(fp_line
			(start 0 0.381)
			(end 0 -0.381)
			(stroke
				(width 0.1524)
				(type default)
			)
			(layer "F.SilkS")
		)
		(fp_line
			(start -0.7874 0.4064)
			(end -0.7874 -0.4064)
			(stroke
				(width 0.1524)
				(type default)
			)
			(layer "F.SilkS")
		)
		(fp_line
			(start -0.7874 -0.4064)
			(end 0.7874 -0.4064)
			(stroke
				(width 0.1524)
				(type default)
			)
			(layer "F.SilkS")
		)
		(fp_poly
			(pts
				(xy -0.5334 0.254) (xy -0.635 0.254) (xy -0.635 0.2286) (xy -0.635 -0.254) (xy -0.5334 -0.254) (xy -0.5334 -0.2794)
				(xy 0.5334 -0.2794) (xy 0.5334 -0.254) (xy 0.635 -0.254) (xy 0.635 0.254) (xy 0.5334 0.254) (xy 0.5334 0.2794)
				(xy -0.508 0.2794) (xy -0.5334 0.2794)
			)
			(stroke
				(width 0)
				(type default)
			)
			(fill no)
			(layer "F.CrtYd")
		)
		(pad "1" smd rect
			(at 0.40005 0 180)
			(size 0.4572 0.508)
			(layers "F.Cu" "F.Mask" "F.Paste")
			(net "P1V9_LAN2")
		)
		(pad "2" smd rect
			(at -0.40005 0 180)
			(size 0.4572 0.508)
			(layers "F.Cu" "F.Mask" "F.Paste")
			(net "GND")
		)
	)
	(footprint ""
		(layer "F.Cu")
		(at 77.506068 -94.131892 -90)
		(property "Reference" "R153"
			(at 55.53329 -24.083264 90)
			(unlocked yes)
			(layer "F.SilkS")
			(effects
				(font
					(size 0.7874 0.5842)
					(thickness 0.1524)
				)
				(justify left)
			)
		)
		(property "Value" ""
			(at 0 0 270)
			(layer "F.Fab")
			(effects
				(font
					(size 1.27 1.27)
				)
			)
		)
		(duplicate_pad_numbers_are_jumpers no)
		(fp_line
			(start -0.7874 0.4064)
			(end -0.7874 -0.4064)
			(stroke
				(width 0.1524)
				(type default)
			)
			(layer "F.SilkS")
		)
		(fp_line
			(start 0.7874 0.4064)
			(end -0.7874 0.4064)
			(stroke
				(width 0.1524)
				(type default)
			)
			(layer "F.SilkS")
		)
		(fp_line
			(start -0.7874 -0.4064)
			(end 0.7874 -0.4064)
			(stroke
				(width 0.1524)
				(type default)
			)
			(layer "F.SilkS")
		)
		(fp_line
			(start 0.7874 -0.4064)
			(end 0.7874 0.4064)
			(stroke
				(width 0.1524)
				(type default)
			)
			(layer "F.SilkS")
		)
		(fp_poly
			(pts
				(xy -0.508 0.2794) (xy -0.508 0.2286) (xy -0.635 0.2286) (xy -0.635 -0.254) (xy -0.5334 -0.254)
				(xy -0.5334 -0.2794) (xy 0.5334 -0.2794) (xy 0.5334 -0.254) (xy 0.635 -0.254) (xy 0.635 0.254) (xy 0.5334 0.254)
				(xy 0.5334 0.2794)
			)
			(stroke
				(width 0)
				(type default)
			)
			(fill no)
			(layer "F.CrtYd")
		)
		(pad "1" smd rect
			(at 0.40005 0 270)
			(size 0.4572 0.508)
			(layers "F.Cu" "F.Mask" "F.Paste")
			(net "PU_CPU_NODE1_BRD_ID0")
		)
		(pad "2" smd rect
			(at -0.40005 0 270)
			(size 0.4572 0.508)
			(layers "F.Cu" "F.Mask" "F.Paste")
			(net "P3V3_NODE1")
		)
	)
	(footprint ""
		(layer "F.Cu")
		(at 36.707572 -72.386698)
		(property "Reference" "R46"
			(at -3.279394 0.381 0)
			(unlocked yes)
			(layer "F.SilkS")
			(effects
				(font
					(size 0.7874 0.5842)
					(thickness 0.1524)
				)
				(justify left)
			)
		)
		(property "Value" ""
			(at 0 0 0)
			(layer "F.Fab")
			(effects
				(font
					(size 1.27 1.27)
				)
			)
		)
		(duplicate_pad_numbers_are_jumpers no)
		(fp_line
			(start -0.7874 -0.4064)
			(end 0.7874 -0.4064)
			(stroke
				(width 0.1524)
				(type default)
			)
			(layer "F.SilkS")
		)
		(fp_line
			(start -0.7874 0.4064)
			(end -0.7874 -0.4064)
			(stroke
				(width 0.1524)
				(type default)
			)
			(layer "F.SilkS")
		)
		(fp_line
			(start 0.7874 -0.4064)
			(end 0.7874 0.4064)
			(stroke
				(width 0.1524)
				(type default)
			)
			(layer "F.SilkS")
		)
		(fp_line
			(start 0.7874 0.4064)
			(end -0.7874 0.4064)
			(stroke
				(width 0.1524)
				(type default)
			)
			(layer "F.SilkS")
		)
		(fp_poly
			(pts
				(xy -0.508 0.2794) (xy -0.508 0.2286) (xy -0.635 0.2286) (xy -0.635 -0.254) (xy -0.5334 -0.254)
				(xy -0.5334 -0.2794) (xy 0.5334 -0.2794) (xy 0.5334 -0.254) (xy 0.635 -0.254) (xy 0.635 0.254) (xy 0.5334 0.254)
				(xy 0.5334 0.2794)
			)
			(stroke
				(width 0)
				(type default)
			)
			(fill no)
			(layer "F.CrtYd")
		)
		(pad "1" smd rect
			(at 0.40005 0)
			(size 0.4572 0.508)
			(layers "F.Cu" "F.Mask" "F.Paste")
			(net "PD_CPU_NODE1_RP1_PERN")
		)
		(pad "2" smd rect
			(at -0.40005 0)
			(size 0.4572 0.508)
			(layers "F.Cu" "F.Mask" "F.Paste")
			(net "GND")
		)
	)
	(footprint ""
		(layer "F.Cu")
		(at 127.652018 -56.418988 -90)
		(property "Reference" "U135"
			(at -2.775966 -1.285748 0)
			(unlocked yes)
			(layer "F.SilkS")
			(effects
				(font
					(size 0.7874 0.5842)
					(thickness 0.1524)
				)
			)
		)
		(property "Value" ""
			(at 0 0 270)
			(layer "F.Fab")
			(effects
				(font
					(size 1.27 1.27)
				)
			)
		)
		(duplicate_pad_numbers_are_jumpers no)
		(fp_line
			(start 1.1176 1.7018)
			(end -1.1176 1.7018)
			(stroke
				(width 0.1524)
				(type default)
			)
			(layer "F.SilkS")
		)
		(fp_line
			(start -1.1176 0.254)
			(end -1.1176 1.7018)
			(stroke
				(width 0.1524)
				(type default)
			)
			(layer "F.SilkS")
		)
		(fp_line
			(start -0.7112 0)
			(end -1.1176 0.254)
			(stroke
				(width 0.1524)
				(type default)
			)
			(layer "F.SilkS")
		)
		(fp_line
			(start -1.1176 -0.254)
			(end -0.7112 0)
			(stroke
				(width 0.1524)
				(type default)
			)
			(layer "F.SilkS")
		)
		(fp_line
			(start -1.1176 -1.7018)
			(end -1.1176 -0.254)
			(stroke
				(width 0.1524)
				(type default)
			)
			(layer "F.SilkS")
		)
		(fp_line
			(start -1.1176 -1.7018)
			(end 1.1176 -1.7018)
			(stroke
				(width 0.1524)
				(type default)
			)
			(layer "F.SilkS")
		)
		(fp_line
			(start 1.1176 -1.7018)
			(end 1.1176 1.7018)
			(stroke
				(width 0.1524)
				(type default)
			)
			(layer "F.SilkS")
		)
		(fp_poly
			(pts
				(xy -0.675386 1.8161) (xy -0.446786 2.4003) (xy -0.878586 2.4003)
			)
			(stroke
				(width 0)
				(type default)
			)
			(fill yes)
			(layer "F.SilkS")
		)
		(fp_rect
			(start -1.1176 1.5494)
			(end 1.1176 -1.5494)
			(stroke
				(width 0)
				(type default)
			)
			(fill no)
			(layer "F.CrtYd")
		)
		(fp_line
			(start 1.1176 1.5494)
			(end -1.1176 1.5494)
			(stroke
				(width 0.1)
				(type default)
			)
			(layer "F.Fab")
		)
		(fp_line
			(start -1.1176 0.254)
			(end -1.1176 1.5494)
			(stroke
				(width 0.1)
				(type default)
			)
			(layer "F.Fab")
		)
		(fp_line
			(start -1.1176 -0.254)
			(end -1.1176 0.254)
			(stroke
				(width 0.1)
				(type default)
			)
			(layer "F.Fab")
		)
		(fp_line
			(start -1.1176 -1.5494)
			(end -1.1176 -0.254)
			(stroke
				(width 0.1)
				(type default)
			)
			(layer "F.Fab")
		)
		(fp_line
			(start -1.1176 -1.5494)
			(end 1.1176 -1.5494)
			(stroke
				(width 0.1)
				(type default)
			)
			(layer "F.Fab")
		)
		(fp_line
			(start 1.1176 -1.5494)
			(end 1.1176 1.5494)
			(stroke
				(width 0.1)
				(type default)
			)
			(layer "F.Fab")
		)
		(fp_poly
			(pts
				(xy -0.675386 1.8161) (xy -0.446786 2.4003) (xy -0.878586 2.4003)
			)
			(stroke
				(width 0)
				(type default)
			)
			(fill yes)
			(layer "F.Fab")
		)
		(pad "1" smd rect
			(at -0.649986 0.962406 270)
			(size 0.3302 1.1684)
			(layers "F.Cu" "F.Mask" "F.Paste")
			(net "COM4_EN_N")
		)
		(pad "2" smd rect
			(at 0 0.962406 270)
			(size 0.3302 1.1684)
			(layers "F.Cu" "F.Mask" "F.Paste")
			(net "UART_TX_P4_BUF")
		)
		(pad "3" smd rect
			(at 0.649986 0.962406 270)
			(size 0.3302 1.1684)
			(layers "F.Cu" "F.Mask" "F.Paste")
			(net "GND")
		)
		(pad "4" smd rect
			(at 0.649986 -0.962406 270)
			(size 0.3302 1.1684)
			(layers "F.Cu" "F.Mask" "F.Paste")
			(net "UART_TX_P4")
		)
		(pad "5" smd rect
			(at -0.649986 -0.962406 270)
			(size 0.3302 1.1684)
			(layers "F.Cu" "F.Mask" "F.Paste")
			(net "P3V3_NODE1")
		)
	)
)
